(kicad_pcb
	(version 20260206)
	(generator "pcbnew")
	(generator_version "10.0")
	(general
		(thickness 1.6)
		(legacy_teardrops no)
	)
	(paper "A4")
	(title_block
		(title "04192023_DAF0TMB3IC0_F0TG_MB_C_brd_V02_OCP.brd")
		(comment 1 "Grand Teton / footprints 7609-7615 of 8354")
	)
	(layers
		(0 "F.Cu" signal "TOP")
		(4 "In1.Cu" signal "GND")
		(6 "In2.Cu" signal "IN1")
		(8 "In3.Cu" signal "GND1")
		(10 "In4.Cu" signal "IN2")
		(12 "In5.Cu" signal "GND2")
		(14 "In6.Cu" signal "IN3")
		(16 "In7.Cu" signal "GND3")
		(18 "In8.Cu" signal "VCC")
		(20 "In9.Cu" signal "VCC1")
		(22 "In10.Cu" signal "GND4")
		(24 "In11.Cu" signal "IN4")
		(26 "In12.Cu" signal "GND5")
		(28 "In13.Cu" signal "IN5")
		(30 "In14.Cu" signal "GND6")
		(32 "In15.Cu" signal "IN6")
		(34 "In16.Cu" signal "GND7")
		(2 "B.Cu" signal "BOTTOM")
		(9 "F.Adhes" user "F.Adhesive")
		(11 "B.Adhes" user "B.Adhesive")
		(13 "F.Paste" user "Package Geometry/Pastemask Top")
		(15 "B.Paste" user "Package Geometry/Pastemask Bottom")
		(5 "F.SilkS" user "Ref Des/Silkscreen Top")
		(7 "B.SilkS" user "Ref Des/Silkscreen Bottom")
		(1 "F.Mask" user "Board Geometry/Soldermask Top")
		(3 "B.Mask" user "Board Geometry/Soldermask Bottom")
		(17 "Dwgs.User" user "User.Drawings")
		(19 "Cmts.User" user "User.Comments")
		(21 "Eco1.User" user "User.Eco1")
		(23 "Eco2.User" user "User.Eco2")
		(25 "Edge.Cuts" user "Board Geometry/Outline")
		(27 "Margin" user)
		(31 "F.CrtYd" user "Package Geometry/Place Bound Top")
		(29 "B.CrtYd" user "Package Geometry/Place Bound Bottom")
		(35 "F.Fab" user "Ref Des/Assembly Top")
		(33 "B.Fab" user "Ref Des/Assembly Bottom")
	)
	(footprint ""
		(layer "B.Cu")
		(at 153.228294 -202.93076 90)
		(property "Reference" "R526"
			(at 0 0 90)
			(layer "B.SilkS")
			(hide yes)
			(effects
				(font
					(size 1.27 1.27)
				)
				(justify mirror)
			)
		)
		(property "Value" ""
			(at 0 0 90)
			(layer "B.Fab")
			(effects
				(font
					(size 1.27 1.27)
				)
				(justify mirror)
			)
		)
		(duplicate_pad_numbers_are_jumpers no)
		(fp_line
			(start 0.7874 -0.4064)
			(end -0.7874 -0.4064)
			(stroke
				(width 0.1524)
				(type default)
			)
			(layer "B.SilkS")
		)
		(fp_line
			(start -0.7874 -0.4064)
			(end -0.7874 0.4064)
			(stroke
				(width 0.1524)
				(type default)
			)
			(layer "B.SilkS")
		)
		(fp_line
			(start 0.7874 0.4064)
			(end 0.7874 -0.4064)
			(stroke
				(width 0.1524)
				(type default)
			)
			(layer "B.SilkS")
		)
		(fp_line
			(start -0.7874 0.4064)
			(end 0.7874 0.4064)
			(stroke
				(width 0.1524)
				(type default)
			)
			(layer "B.SilkS")
		)
		(fp_line
			(start 0.67945 -0.305054)
			(end 0.12065 -0.305054)
			(stroke
				(width 0.1)
				(type default)
			)
			(layer "B.Fab")
		)
		(fp_line
			(start 0.12065 -0.305054)
			(end 0.12065 -0.2794)
			(stroke
				(width 0.1)
				(type default)
			)
			(layer "B.Fab")
		)
		(fp_line
			(start -0.12065 -0.3048)
			(end -0.67945 -0.3048)
			(stroke
				(width 0.1)
				(type default)
			)
			(layer "B.Fab")
		)
		(fp_line
			(start -0.67945 -0.3048)
			(end -0.67945 0.3048)
			(stroke
				(width 0.1)
				(type default)
			)
			(layer "B.Fab")
		)
		(fp_line
			(start 0.12065 -0.2794)
			(end -0.12065 -0.2794)
			(stroke
				(width 0.1)
				(type default)
			)
			(layer "B.Fab")
		)
		(fp_line
			(start -0.12065 -0.2794)
			(end -0.12065 -0.3048)
			(stroke
				(width 0.1)
				(type default)
			)
			(layer "B.Fab")
		)
		(fp_line
			(start 0.12065 0.2794)
			(end 0.12065 0.3048)
			(stroke
				(width 0.1)
				(type default)
			)
			(layer "B.Fab")
		)
		(fp_line
			(start -0.120396 0.2794)
			(end 0.12065 0.2794)
			(stroke
				(width 0.1)
				(type default)
			)
			(layer "B.Fab")
		)
		(fp_line
			(start 0.67945 0.3048)
			(end 0.67945 -0.305054)
			(stroke
				(width 0.1)
				(type default)
			)
			(layer "B.Fab")
		)
		(fp_line
			(start 0.12065 0.3048)
			(end 0.67945 0.3048)
			(stroke
				(width 0.1)
				(type default)
			)
			(layer "B.Fab")
		)
		(fp_line
			(start -0.120396 0.3048)
			(end -0.120396 0.2794)
			(stroke
				(width 0.1)
				(type default)
			)
			(layer "B.Fab")
		)
		(fp_line
			(start -0.67945 0.3048)
			(end -0.120396 0.3048)
			(stroke
				(width 0.1)
				(type default)
			)
			(layer "B.Fab")
		)
		(pad "1" smd circle
			(at 0.40005 0 270)
			(size 0 0)
			(layers "B.Cu" "B.Mask" "B.Paste")
			(net "PVDD18_S5_P1")
		)
		(pad "2" smd circle
			(at -0.40005 0 270)
			(size 0 0)
			(layers "B.Cu" "B.Mask" "B.Paste")
			(net "JTAG_CPU1_TCK")
		)
	)
	(footprint ""
		(layer "B.Cu")
		(at 104.561386 -264.354564)
		(property "Reference" "C2490"
			(at 0 0 0)
			(layer "B.SilkS")
			(hide yes)
			(effects
				(font
					(size 1.27 1.27)
				)
				(justify mirror)
			)
		)
		(property "Value" ""
			(at 0 0 0)
			(layer "B.Fab")
			(effects
				(font
					(size 1.27 1.27)
				)
				(justify mirror)
			)
		)
		(duplicate_pad_numbers_are_jumpers no)
		(fp_line
			(start -0.7874 -0.4064)
			(end -0.7874 0.4064)
			(stroke
				(width 0.1524)
				(type default)
			)
			(layer "B.SilkS")
		)
		(fp_line
			(start -0.7874 0.4064)
			(end 0.7874 0.4064)
			(stroke
				(width 0.1524)
				(type default)
			)
			(layer "B.SilkS")
		)
		(fp_line
			(start 0.7874 -0.4064)
			(end -0.7874 -0.4064)
			(stroke
				(width 0.1524)
				(type default)
			)
			(layer "B.SilkS")
		)
		(fp_line
			(start 0.7874 0.4064)
			(end 0.7874 -0.4064)
			(stroke
				(width 0.1524)
				(type default)
			)
			(layer "B.SilkS")
		)
		(fp_line
			(start -0.67945 -0.3048)
			(end -0.67945 0.3048)
			(stroke
				(width 0.1)
				(type default)
			)
			(layer "B.Fab")
		)
		(fp_line
			(start -0.67945 0.3048)
			(end -0.120396 0.3048)
			(stroke
				(width 0.1)
				(type default)
			)
			(layer "B.Fab")
		)
		(fp_line
			(start -0.12065 -0.3048)
			(end -0.67945 -0.3048)
			(stroke
				(width 0.1)
				(type default)
			)
			(layer "B.Fab")
		)
		(fp_line
			(start -0.12065 -0.2794)
			(end -0.12065 -0.3048)
			(stroke
				(width 0.1)
				(type default)
			)
			(layer "B.Fab")
		)
		(fp_line
			(start -0.120396 0.2794)
			(end 0.12065 0.2794)
			(stroke
				(width 0.1)
				(type default)
			)
			(layer "B.Fab")
		)
		(fp_line
			(start -0.120396 0.3048)
			(end -0.120396 0.2794)
			(stroke
				(width 0.1)
				(type default)
			)
			(layer "B.Fab")
		)
		(fp_line
			(start 0.12065 -0.305054)
			(end 0.12065 -0.2794)
			(stroke
				(width 0.1)
				(type default)
			)
			(layer "B.Fab")
		)
		(fp_line
			(start 0.12065 -0.2794)
			(end -0.12065 -0.2794)
			(stroke
				(width 0.1)
				(type default)
			)
			(layer "B.Fab")
		)
		(fp_line
			(start 0.12065 0.2794)
			(end 0.12065 0.3048)
			(stroke
				(width 0.1)
				(type default)
			)
			(layer "B.Fab")
		)
		(fp_line
			(start 0.12065 0.3048)
			(end 0.67945 0.3048)
			(stroke
				(width 0.1)
				(type default)
			)
			(layer "B.Fab")
		)
		(fp_line
			(start 0.67945 -0.305054)
			(end 0.12065 -0.305054)
			(stroke
				(width 0.1)
				(type default)
			)
			(layer "B.Fab")
		)
		(fp_line
			(start 0.67945 0.3048)
			(end 0.67945 -0.305054)
			(stroke
				(width 0.1)
				(type default)
			)
			(layer "B.Fab")
		)
		(pad "1" smd circle
			(at 0.40005 0 180)
			(size 0 0)
			(layers "B.Cu" "B.Mask" "B.Paste")
			(net "PVDD11_S3_P1")
		)
		(pad "2" smd circle
			(at -0.40005 0 180)
			(size 0 0)
			(layers "B.Cu" "B.Mask" "B.Paste")
			(net "GND")
		)
	)
	(footprint ""
		(layer "B.Cu")
		(at 377.818396 -396.393162 -90)
		(property "Reference" "C1000"
			(at 0 0 90)
			(layer "B.SilkS")
			(hide yes)
			(effects
				(font
					(size 1.27 1.27)
				)
				(justify mirror)
			)
		)
		(property "Value" ""
			(at 0 0 90)
			(layer "B.Fab")
			(effects
				(font
					(size 1.27 1.27)
				)
				(justify mirror)
			)
		)
		(duplicate_pad_numbers_are_jumpers no)
		(fp_line
			(start -0.299974 0.150114)
			(end 0.299974 0.150114)
			(stroke
				(width 0.1)
				(type default)
			)
			(layer "B.Fab")
		)
		(fp_line
			(start 0.299974 0.150114)
			(end 0.299974 -0.150114)
			(stroke
				(width 0.1)
				(type default)
			)
			(layer "B.Fab")
		)
		(fp_line
			(start -0.299974 -0.150114)
			(end -0.299974 0.150114)
			(stroke
				(width 0.1)
				(type default)
			)
			(layer "B.Fab")
		)
		(fp_line
			(start 0.299974 -0.150114)
			(end -0.299974 -0.150114)
			(stroke
				(width 0.1)
				(type default)
			)
			(layer "B.Fab")
		)
		(pad "1" smd rect
			(at 0.2667 0 90)
			(size 0.3048 0.381)
			(layers "B.Cu" "B.Mask" "B.Paste")
			(net "P1V8_CPU0_RT3_1A")
		)
		(pad "2" smd rect
			(at -0.2667 0 90)
			(size 0.3048 0.381)
			(layers "B.Cu" "B.Mask" "B.Paste")
			(net "GND")
		)
	)
	(footprint ""
		(layer "B.Cu")
		(at 150.97887 -13.762228 90)
		(property "Reference" "R2417"
			(at 0 0 90)
			(layer "B.SilkS")
			(hide yes)
			(effects
				(font
					(size 1.27 1.27)
				)
				(justify mirror)
			)
		)
		(property "Value" ""
			(at 0 0 90)
			(layer "B.Fab")
			(effects
				(font
					(size 1.27 1.27)
				)
				(justify mirror)
			)
		)
		(duplicate_pad_numbers_are_jumpers no)
		(fp_line
			(start 0.7874 -0.4064)
			(end -0.7874 -0.4064)
			(stroke
				(width 0.1524)
				(type default)
			)
			(layer "B.SilkS")
		)
		(fp_line
			(start -0.7874 -0.4064)
			(end -0.7874 0.4064)
			(stroke
				(width 0.1524)
				(type default)
			)
			(layer "B.SilkS")
		)
		(fp_line
			(start 0.7874 0.4064)
			(end 0.7874 -0.4064)
			(stroke
				(width 0.1524)
				(type default)
			)
			(layer "B.SilkS")
		)
		(fp_line
			(start -0.7874 0.4064)
			(end 0.7874 0.4064)
			(stroke
				(width 0.1524)
				(type default)
			)
			(layer "B.SilkS")
		)
		(fp_line
			(start 0.67945 -0.305054)
			(end 0.12065 -0.305054)
			(stroke
				(width 0.1)
				(type default)
			)
			(layer "B.Fab")
		)
		(fp_line
			(start 0.12065 -0.305054)
			(end 0.12065 -0.2794)
			(stroke
				(width 0.1)
				(type default)
			)
			(layer "B.Fab")
		)
		(fp_line
			(start -0.12065 -0.3048)
			(end -0.67945 -0.3048)
			(stroke
				(width 0.1)
				(type default)
			)
			(layer "B.Fab")
		)
		(fp_line
			(start -0.67945 -0.3048)
			(end -0.67945 0.3048)
			(stroke
				(width 0.1)
				(type default)
			)
			(layer "B.Fab")
		)
		(fp_line
			(start 0.12065 -0.2794)
			(end -0.12065 -0.2794)
			(stroke
				(width 0.1)
				(type default)
			)
			(layer "B.Fab")
		)
		(fp_line
			(start -0.12065 -0.2794)
			(end -0.12065 -0.3048)
			(stroke
				(width 0.1)
				(type default)
			)
			(layer "B.Fab")
		)
		(fp_line
			(start 0.12065 0.2794)
			(end 0.12065 0.3048)
			(stroke
				(width 0.1)
				(type default)
			)
			(layer "B.Fab")
		)
		(fp_line
			(start -0.120396 0.2794)
			(end 0.12065 0.2794)
			(stroke
				(width 0.1)
				(type default)
			)
			(layer "B.Fab")
		)
		(fp_line
			(start 0.67945 0.3048)
			(end 0.67945 -0.305054)
			(stroke
				(width 0.1)
				(type default)
			)
			(layer "B.Fab")
		)
		(fp_line
			(start 0.12065 0.3048)
			(end 0.67945 0.3048)
			(stroke
				(width 0.1)
				(type default)
			)
			(layer "B.Fab")
		)
		(fp_line
			(start -0.120396 0.3048)
			(end -0.120396 0.2794)
			(stroke
				(width 0.1)
				(type default)
			)
			(layer "B.Fab")
		)
		(fp_line
			(start -0.67945 0.3048)
			(end -0.120396 0.3048)
			(stroke
				(width 0.1)
				(type default)
			)
			(layer "B.Fab")
		)
		(pad "1" smd circle
			(at 0.40005 0 270)
			(size 0 0)
			(layers "B.Cu" "B.Mask" "B.Paste")
			(net "SMB_HOST_CLK_3V3AUX_SCL")
		)
		(pad "2" smd circle
			(at -0.40005 0 270)
			(size 0 0)
			(layers "B.Cu" "B.Mask" "B.Paste")
			(net "SMB_HOST_CLK_3V3AUX_SCL_R0")
		)
	)
	(footprint ""
		(layer "B.Cu")
		(at 113.71834 -61.76391 -90)
		(property "Reference" "R6225"
			(at 0 0 90)
			(layer "B.SilkS")
			(hide yes)
			(effects
				(font
					(size 1.27 1.27)
				)
				(justify mirror)
			)
		)
		(property "Value" ""
			(at 0 0 90)
			(layer "B.Fab")
			(effects
				(font
					(size 1.27 1.27)
				)
				(justify mirror)
			)
		)
		(duplicate_pad_numbers_are_jumpers no)
		(fp_line
			(start -0.7874 0.4064)
			(end 0.7874 0.4064)
			(stroke
				(width 0.1524)
				(type default)
			)
			(layer "B.SilkS")
		)
		(fp_line
			(start 0.7874 0.4064)
			(end 0.7874 -0.4064)
			(stroke
				(width 0.1524)
				(type default)
			)
			(layer "B.SilkS")
		)
		(fp_line
			(start -0.7874 -0.4064)
			(end -0.7874 0.4064)
			(stroke
				(width 0.1524)
				(type default)
			)
			(layer "B.SilkS")
		)
		(fp_line
			(start 0.7874 -0.4064)
			(end -0.7874 -0.4064)
			(stroke
				(width 0.1524)
				(type default)
			)
			(layer "B.SilkS")
		)
		(fp_line
			(start -0.67945 0.3048)
			(end -0.120396 0.3048)
			(stroke
				(width 0.1)
				(type default)
			)
			(layer "B.Fab")
		)
		(fp_line
			(start -0.120396 0.3048)
			(end -0.120396 0.2794)
			(stroke
				(width 0.1)
				(type default)
			)
			(layer "B.Fab")
		)
		(fp_line
			(start 0.12065 0.3048)
			(end 0.67945 0.3048)
			(stroke
				(width 0.1)
				(type default)
			)
			(layer "B.Fab")
		)
		(fp_line
			(start 0.67945 0.3048)
			(end 0.67945 -0.305054)
			(stroke
				(width 0.1)
				(type default)
			)
			(layer "B.Fab")
		)
		(fp_line
			(start -0.120396 0.2794)
			(end 0.12065 0.2794)
			(stroke
				(width 0.1)
				(type default)
			)
			(layer "B.Fab")
		)
		(fp_line
			(start 0.12065 0.2794)
			(end 0.12065 0.3048)
			(stroke
				(width 0.1)
				(type default)
			)
			(layer "B.Fab")
		)
		(fp_line
			(start -0.12065 -0.2794)
			(end -0.12065 -0.3048)
			(stroke
				(width 0.1)
				(type default)
			)
			(layer "B.Fab")
		)
		(fp_line
			(start 0.12065 -0.2794)
			(end -0.12065 -0.2794)
			(stroke
				(width 0.1)
				(type default)
			)
			(layer "B.Fab")
		)
		(fp_line
			(start -0.67945 -0.3048)
			(end -0.67945 0.3048)
			(stroke
				(width 0.1)
				(type default)
			)
			(layer "B.Fab")
		)
		(fp_line
			(start -0.12065 -0.3048)
			(end -0.67945 -0.3048)
			(stroke
				(width 0.1)
				(type default)
			)
			(layer "B.Fab")
		)
		(fp_line
			(start 0.12065 -0.305054)
			(end 0.12065 -0.2794)
			(stroke
				(width 0.1)
				(type default)
			)
			(layer "B.Fab")
		)
		(fp_line
			(start 0.67945 -0.305054)
			(end 0.12065 -0.305054)
			(stroke
				(width 0.1)
				(type default)
			)
			(layer "B.Fab")
		)
		(pad "1" smd circle
			(at 0.40005 0 90)
			(size 0 0)
			(layers "B.Cu" "B.Mask" "B.Paste")
			(net "SMB_USB_CPU0_HUB1_SDA")
		)
		(pad "2" smd circle
			(at -0.40005 0 90)
			(size 0 0)
			(layers "B.Cu" "B.Mask" "B.Paste")
			(net "SMB_USB_CPU0_HUB1_SDA_R2")
		)
	)
	(footprint ""
		(layer "B.Cu")
		(at 353.900232 -258.405122 180)
		(property "Reference" "C2638"
			(at 0 0 0)
			(layer "B.SilkS")
			(hide yes)
			(effects
				(font
					(size 1.27 1.27)
				)
				(justify mirror)
			)
		)
		(property "Value" ""
			(at 0 0 0)
			(layer "B.Fab")
			(effects
				(font
					(size 1.27 1.27)
				)
				(justify mirror)
			)
		)
		(duplicate_pad_numbers_are_jumpers no)
		(fp_line
			(start 0.7874 0.4064)
			(end 0.7874 -0.4064)
			(stroke
				(width 0.1524)
				(type default)
			)
			(layer "B.SilkS")
		)
		(fp_line
			(start 0.7874 -0.4064)
			(end -0.7874 -0.4064)
			(stroke
				(width 0.1524)
				(type default)
			)
			(layer "B.SilkS")
		)
		(fp_line
			(start -0.7874 0.4064)
			(end 0.7874 0.4064)
			(stroke
				(width 0.1524)
				(type default)
			)
			(layer "B.SilkS")
		)
		(fp_line
			(start -0.7874 -0.4064)
			(end -0.7874 0.4064)
			(stroke
				(width 0.1524)
				(type default)
			)
			(layer "B.SilkS")
		)
		(fp_line
			(start 0.67945 0.3048)
			(end 0.67945 -0.305054)
			(stroke
				(width 0.1)
				(type default)
			)
			(layer "B.Fab")
		)
		(fp_line
			(start 0.67945 -0.305054)
			(end 0.12065 -0.305054)
			(stroke
				(width 0.1)
				(type default)
			)
			(layer "B.Fab")
		)
		(fp_line
			(start 0.12065 0.3048)
			(end 0.67945 0.3048)
			(stroke
				(width 0.1)
				(type default)
			)
			(layer "B.Fab")
		)
		(fp_line
			(start 0.12065 0.2794)
			(end 0.12065 0.3048)
			(stroke
				(width 0.1)
				(type default)
			)
			(layer "B.Fab")
		)
		(fp_line
			(start 0.12065 -0.2794)
			(end -0.12065 -0.2794)
			(stroke
				(width 0.1)
				(type default)
			)
			(layer "B.Fab")
		)
		(fp_line
			(start 0.12065 -0.305054)
			(end 0.12065 -0.2794)
			(stroke
				(width 0.1)
				(type default)
			)
			(layer "B.Fab")
		)
		(fp_line
			(start -0.120396 0.3048)
			(end -0.120396 0.2794)
			(stroke
				(width 0.1)
				(type default)
			)
			(layer "B.Fab")
		)
		(fp_line
			(start -0.120396 0.2794)
			(end 0.12065 0.2794)
			(stroke
				(width 0.1)
				(type default)
			)
			(layer "B.Fab")
		)
		(fp_line
			(start -0.12065 -0.2794)
			(end -0.12065 -0.3048)
			(stroke
				(width 0.1)
				(type default)
			)
			(layer "B.Fab")
		)
		(fp_line
			(start -0.12065 -0.3048)
			(end -0.67945 -0.3048)
			(stroke
				(width 0.1)
				(type default)
			)
			(layer "B.Fab")
		)
		(fp_line
			(start -0.67945 0.3048)
			(end -0.120396 0.3048)
			(stroke
				(width 0.1)
				(type default)
			)
			(layer "B.Fab")
		)
		(fp_line
			(start -0.67945 -0.3048)
			(end -0.67945 0.3048)
			(stroke
				(width 0.1)
				(type default)
			)
			(layer "B.Fab")
		)
		(pad "1" smd circle
			(at 0.40005 0)
			(size 0 0)
			(layers "B.Cu" "B.Mask" "B.Paste")
			(net "PVDDIO_P0")
		)
		(pad "2" smd circle
			(at -0.40005 0)
			(size 0 0)
			(layers "B.Cu" "B.Mask" "B.Paste")
			(net "GND")
		)
	)
	(footprint ""
		(layer "B.Cu")
		(at 121.810272 -71.397622 180)
		(property "Reference" "C6085"
			(at 0 0 0)
			(layer "B.SilkS")
			(hide yes)
			(effects
				(font
					(size 1.27 1.27)
				)
				(justify mirror)
			)
		)
		(property "Value" ""
			(at 0 0 0)
			(layer "B.Fab")
			(effects
				(font
					(size 1.27 1.27)
				)
				(justify mirror)
			)
		)
		(duplicate_pad_numbers_are_jumpers no)
		(fp_line
			(start 0.7874 0.4064)
			(end 0.7874 -0.4064)
			(stroke
				(width 0.1524)
				(type default)
			)
			(layer "B.SilkS")
		)
		(fp_line
			(start 0.7874 -0.4064)
			(end -0.7874 -0.4064)
			(stroke
				(width 0.1524)
				(type default)
			)
			(layer "B.SilkS")
		)
		(fp_line
			(start -0.7874 0.4064)
			(end 0.7874 0.4064)
			(stroke
				(width 0.1524)
				(type default)
			)
			(layer "B.SilkS")
		)
		(fp_line
			(start -0.7874 -0.4064)
			(end -0.7874 0.4064)
			(stroke
				(width 0.1524)
				(type default)
			)
			(layer "B.SilkS")
		)
		(fp_line
			(start 0.67945 0.3048)
			(end 0.67945 -0.305054)
			(stroke
				(width 0.1)
				(type default)
			)
			(layer "B.Fab")
		)
		(fp_line
			(start 0.67945 -0.305054)
			(end 0.12065 -0.305054)
			(stroke
				(width 0.1)
				(type default)
			)
			(layer "B.Fab")
		)
		(fp_line
			(start 0.12065 0.3048)
			(end 0.67945 0.3048)
			(stroke
				(width 0.1)
				(type default)
			)
			(layer "B.Fab")
		)
		(fp_line
			(start 0.12065 0.2794)
			(end 0.12065 0.3048)
			(stroke
				(width 0.1)
				(type default)
			)
			(layer "B.Fab")
		)
		(fp_line
			(start 0.12065 -0.2794)
			(end -0.12065 -0.2794)
			(stroke
				(width 0.1)
				(type default)
			)
			(layer "B.Fab")
		)
		(fp_line
			(start 0.12065 -0.305054)
			(end 0.12065 -0.2794)
			(stroke
				(width 0.1)
				(type default)
			)
			(layer "B.Fab")
		)
		(fp_line
			(start -0.120396 0.3048)
			(end -0.120396 0.2794)
			(stroke
				(width 0.1)
				(type default)
			)
			(layer "B.Fab")
		)
		(fp_line
			(start -0.120396 0.2794)
			(end 0.12065 0.2794)
			(stroke
				(width 0.1)
				(type default)
			)
			(layer "B.Fab")
		)
		(fp_line
			(start -0.12065 -0.2794)
			(end -0.12065 -0.3048)
			(stroke
				(width 0.1)
				(type default)
			)
			(layer "B.Fab")
		)
		(fp_line
			(start -0.12065 -0.3048)
			(end -0.67945 -0.3048)
			(stroke
				(width 0.1)
				(type default)
			)
			(layer "B.Fab")
		)
		(fp_line
			(start -0.67945 0.3048)
			(end -0.120396 0.3048)
			(stroke
				(width 0.1)
				(type default)
			)
			(layer "B.Fab")
		)
		(fp_line
			(start -0.67945 -0.3048)
			(end -0.67945 0.3048)
			(stroke
				(width 0.1)
				(type default)
			)
			(layer "B.Fab")
		)
		(pad "1" smd circle
			(at 0.40005 0)
			(size 0 0)
			(layers "B.Cu" "B.Mask" "B.Paste")
			(net "PWRGD_P1V8_AUX_R")
		)
		(pad "2" smd circle
			(at -0.40005 0)
			(size 0 0)
			(layers "B.Cu" "B.Mask" "B.Paste")
			(net "GND")
		)
	)
)
